FILE_TYPE = CONNECTIVITY;
{Allegro Design Entry HDL 17.2-2016 S081 (4005846) 1/11/2022}
"PAGE_NUMBER" = 200;
0"NC";
1"GND\g";
2"GND\g";
3"GND\g";
4"GND\g";
5"GND\g";
6"GND\g";
7"P5V_STBY\g";
8"P3V3_STBY\g";
9"GND\g";
10"GND\g";
11"GND\g";
12"GND\g";
13"PVDD11_S3_P1\g";
14"SW_PVDD11_S3_P1_PH2";
15"SW_PVDD11_S3_P1_SW2";
16"SW_PVDD11_S3_P1_PH1";
17"SW_PVDD11_S3_P1_SW1";
18"PVDD11_S3_P1_PVCC\g";
19"PVDD11_S3_P1_VCCS";
20"PVDD11_S3_P1_PWM2";
21"PVDD11_S3_P1_VCC2";
22"PVDD11_S3_P1_LSET2";
23"NC_PVDD11_S3_P1_DNC2";
24"PVDD11_S3_P1_TEMP0";
25"PVDD11_S3_P1_IMON2";
26"PVDD11_S3_P1_PVCC\g";
27"PVDD11_S3_P1_PWM1";
28"PVDD11_S3_P1_TEMP0";
29"GND\g";
30"NC_PVDD11_S3_P1_GL1_2";
31"NC_PVDD11_S3_P1_GL2_2";
32"SW_PVDD11_S3_P1_BOOT2";
33"SW_PVDD11_S3_P1_SW2_RC";
34"PVDD11_S3_P1_VOS2";
35"SW_P12V_STBY_PVDD11_S3_P1_FLT\g";
36"GND\g";
37"GND\g";
38"SW_PVDD11_S3_P1_SW1_RC";
39"PVDD11_S3_P1_VCCS";
40"PVDD11_S3_P1_VCC1";
41"PVDD11_S3_P1_IMON1";
42"PVDD11_S3_P1_LSET1";
43"NC_PVDD11_S3_P1_DNC1";
44"NC_PVDD11_S3_P1_GL2_1";
45"NC_PVDD11_S3_P1_GL1_1";
46"SW_P12V_STBY_PVDD11_S3_P1_FLT\g";
47"GND\g";
48"SW_PVDD11_S3_P1_BOOT1";
49"PVDD11_S3_P1_VOS1";
50"SW_PVDD11_S3_P1_BOOT2_RC";
51"PVDD11_S3_P1\g";
52"GND\g";
53"PVDD11_S3_P1\g";
54"GND\g";
55"PVDD11_S3_P1\g";
56"GND\g";
57"GND\g";
58"SW_PVDD11_S3_P1_BOOT1_RC";
59"P12V_STBY\g";
%"Q_INDUCTOR"
"1","(-3350,4500)","0","pure_quanta","I101";
;
LOCATION"PL54"
$SEC"1"
CDS_SEC"1"
MATERIAL"IND"
VALUE"90NH/155AA"
PART_NUMBER"CVA90^0KZ04"
PACK_TYPE"SMLF"
CDS_LIB"pure_quanta"
NEEDS_NO_SIZE"TRUE";
"1"
$PN"1"17;
"2"
$PN"2"13;
%"VCC_CORE"
"1","(-3900,5650)","0","pure_quanta_power","I104";
;
HDL_POWER"SW_P12V_STBY_PVDD11_S3_P1_FLT"
CDS_LIB"pure_quanta_power";
"A"46;
%"Q_INDUCTOR"
"1","(-3300,1575)","0","pure_quanta","I105";
;
LOCATION"PL55"
$SEC"1"
CDS_SEC"1"
MATERIAL"IND"
VALUE"90NH/155AA"
PART_NUMBER"CVA90^0KZ04"
PACK_TYPE"SMLF"
NEEDS_NO_SIZE"TRUE"
CDS_LIB"pure_quanta";
"1"
$PN"1"15;
"2"
$PN"2"51;
%"Q_CAP"
"1","(-4075,2450)","0","pure_quanta","I107";
;
LOCATION"PC518_2"
$SEC"1"
CDS_SEC"1"
MATERIAL"X6S"
TOLERANCE"10%"
VALUE"10UF"
PART_NUMBER"CH6104KEA00"
VOLTAGE"25V"
PACK_TYPE"C0805"
CDS_LIB"pure_quanta";
"B"
$PN"2"37;
"A"
$PN"1"35;
%"Q_RES"
"1","(-3600,3350)","0","pure_quanta","I110";
;
LOCATION"PR332"
$SEC"1"
CDS_SEC"1"
WATTAGE"1/16W"
MATERIAL"CHIP"
TOLERANCE"5%"
VALUE"0"
PART_NUMBER"CS00002JB38"
PACK_TYPE"0402LF"
CDS_LIB"pure_quanta";
"B"
$PN"2"13;
"A"
$PN"1"49;
%"Q_RES"
"1","(-3525,550)","0","pure_quanta","I111";
;
LOCATION"PR333"
$SEC"1"
CDS_SEC"1"
WATTAGE"1/16W"
MATERIAL"CHIP"
TOLERANCE"5%"
VALUE"0"
PART_NUMBER"CS00002JB38"
PACK_TYPE"0402LF"
CDS_LIB"pure_quanta";
"B"
$PN"2"51;
"A"
$PN"1"34;
%"Q_CAPP"
"1","(-2575,2625)","0","pure_quanta","I118";
;
LOCATION"PC528"
$SEC"1"
CDS_SEC"1"
MATERIAL"SPCAP"
TOLERANCE"20%"
VALUE"470UF"
PART_NUMBER"CH747LM8825"
VOLTAGE"2.5V"
PACK_TYPE"SMLF"
CDS_LIB"pure_quanta";
"A"
$PN"1"53;
"B"
$PN"2"52;
%"Q_CAPP"
"1","(-1800,2650)","0","pure_quanta","I119";
;
LOCATION"PC530"
$SEC"1"
CDS_SEC"1"
MATERIAL"OSCON"
TOLERANCE"20%"
VALUE"390UF"
PART_NUMBER"CC7390JMZ12"
VOLTAGE"2.5V"
PACK_TYPE"SMLF"
CDS_LIB"pure_quanta";
"A"
$PN"1"55;
"B"
$PN"2"56;
%"Q_CAPP"
"1","(-1475,2650)","0","pure_quanta","I120";
;
LOCATION"PC531"
$SEC"1"
CDS_SEC"1"
MATERIAL"OSCON"
TOLERANCE"20%"
VALUE"390UF"
PART_NUMBER"CC7390JMZ12"
VOLTAGE"2.5V"
PACK_TYPE"SMLF"
CDS_LIB"pure_quanta";
"A"
$PN"1"55;
"B"
$PN"2"56;
%"Q_CAPP"
"1","(-1150,2650)","0","pure_quanta","I121";
;
LOCATION"PC532"
$SEC"1"
CDS_SEC"1"
MATERIAL"OSCON"
TOLERANCE"20%"
VALUE"390UF"
PART_NUMBER"CC7390JMZ12"
VOLTAGE"2.5V"
PACK_TYPE"SMLF"
CDS_LIB"pure_quanta";
"A"
$PN"1"55;
"B"
$PN"2"56;
%"VCC_CORE"
"1","(-1800,2875)","0","pure_quanta_power","I122";
;
HDL_POWER"PVDD11_S3_P1"
CDS_LIB"pure_quanta_power";
"A"55;
%"UNIVERSAL_GND"
"1","(-1800,2325)","0","pure_quanta_power","I123";
;
CDS_LIB"pure_quanta_power"
HDL_POWER"GND";
"A"56;
%"Q_CAP"
"1","(-5075,5375)","0","pure_quanta","I124";
;
LOCATION"PC511_1"
$SEC"1"
CDS_SEC"1"
MATERIAL"X7R"
TOLERANCE"10%"
VALUE"0.1UF"
PART_NUMBER"CH4104K1B00"
VOLTAGE"25V"
PACK_TYPE"0402"
CDS_LIB"pure_quanta";
"B"
$PN"2"47;
"A"
$PN"1"46;
%"Q_CAP"
"1","(-5025,2450)","0","pure_quanta","I125";
;
LOCATION"PC512_2"
$SEC"1"
CDS_SEC"1"
MATERIAL"X7R"
TOLERANCE"10%"
VALUE"0.1UF"
PART_NUMBER"CH4104K1B00"
VOLTAGE"25V"
PACK_TYPE"0402"
CDS_LIB"pure_quanta";
"B"
$PN"2"37;
"A"
$PN"1"35;
%"Q_CAP"
"1","(-7800,4800)","0","pure_quanta","I126";
;
LOCATION"PC505"
$SEC"1"
CDS_SEC"1"
MATERIAL"X6S"
TOLERANCE"10%"
VALUE"2.2UF"
PART_NUMBER"CH5222KEB01"
VOLTAGE"10V"
PACK_TYPE"C0402"
CDS_LIB"pure_quanta";
"B"
$PN"2"1;
"A"
$PN"1"40;
%"UNIVERSAL_GND"
"1","(-7800,4600)","0","pure_quanta_power","I127";
;
CDS_LIB"pure_quanta_power"
HDL_POWER"GND";
"A"1;
%"UNIVERSAL_GND"
"1","(-7450,5100)","0","pure_quanta_power","I128";
;
CDS_LIB"pure_quanta_power"
HDL_POWER"GND";
"A"2;
%"Q_RES"
"2","(-7800,5350)","0","pure_quanta","I129";
;
LOCATION"PR326"
$SEC"1"
CDS_SEC"1"
WATTAGE"1/16W"
MATERIAL"CHIP"
TOLERANCE"1%"
VALUE"2.2"
PART_NUMBER"CS-2202FB00"
PACK_TYPE"0402LF"
CDS_LIB"pure_quanta";
"A"
$PN"1"18;
"B"
$PN"2"40;
%"Q_CAP"
"1","(-7450,5375)","0","pure_quanta","I130";
;
LOCATION"PC507_11P1_1"
$SEC"1"
CDS_SEC"1"
MATERIAL"X6S"
TOLERANCE"10%"
VALUE"2.2UF"
PART_NUMBER"CH5222KEB01"
VOLTAGE"10V"
PACK_TYPE"C0402"
CDS_LIB"pure_quanta";
"B"
$PN"2"2;
"A"
$PN"1"18;
%"VCC_CORE"
"1","(-7625,5950)","0","pure_quanta_power","I131";
;
HDL_POWER"PVDD11_S3_P1_PVCC"
CDS_LIB"pure_quanta_power";
"A"18;
%"Q_CAP"
"1","(-7800,1875)","0","pure_quanta","I132";
;
LOCATION"PC506"
$SEC"1"
CDS_SEC"1"
MATERIAL"X6S"
TOLERANCE"10%"
VALUE"2.2UF"
PART_NUMBER"CH5222KEB01"
VOLTAGE"10V"
PACK_TYPE"C0402"
CDS_LIB"pure_quanta";
"B"
$PN"2"3;
"A"
$PN"1"21;
%"UNIVERSAL_GND"
"1","(-7800,1675)","0","pure_quanta_power","I133";
;
CDS_LIB"pure_quanta_power"
HDL_POWER"GND";
"A"3;
%"UNIVERSAL_GND"
"1","(-7450,2175)","0","pure_quanta_power","I134";
;
CDS_LIB"pure_quanta_power"
HDL_POWER"GND";
"A"4;
%"Q_RES"
"2","(-7800,2425)","0","pure_quanta","I135";
;
LOCATION"PR327"
$SEC"1"
CDS_SEC"1"
WATTAGE"1/16W"
MATERIAL"CHIP"
TOLERANCE"1%"
VALUE"2.2"
PART_NUMBER"CS-2202FB00"
PACK_TYPE"0402LF"
CDS_LIB"pure_quanta";
"A"
$PN"1"26;
"B"
$PN"2"21;
%"Q_CAP"
"1","(-7450,2450)","0","pure_quanta","I136";
;
LOCATION"PC508_11P1_2"
$SEC"1"
CDS_SEC"1"
MATERIAL"X6S"
TOLERANCE"10%"
VALUE"2.2UF"
PART_NUMBER"CH5222KEB01"
VOLTAGE"10V"
PACK_TYPE"C0402"
CDS_LIB"pure_quanta";
"B"
$PN"2"4;
"A"
$PN"1"26;
%"Q_CAP"
"1","(-3775,5375)","0","pure_quanta","I138";
;
LOCATION"PC521_1"
$SEC"1"
CDS_SEC"1"
MATERIAL"X6S"
TOLERANCE"10%"
VALUE"10UF"
PART_NUMBER"CH6104KEA00"
VOLTAGE"25V"
PACK_TYPE"C0805"
CDS_LIB"pure_quanta";
"B"
$PN"2"47;
"A"
$PN"1"46;
%"Q_CAP"
"1","(-3750,2450)","0","pure_quanta","I139";
;
LOCATION"PC27"
$SEC"1"
CDS_SEC"1"
MATERIAL"X6S"
TOLERANCE"10%"
VALUE"10UF"
PART_NUMBER"CH6104KEA00"
VOLTAGE"25V"
PACK_TYPE"C0805"
CDS_LIB"pure_quanta";
"B"
$PN"2"37;
"A"
$PN"1"35;
%"UNIVERSAL_GND"
"1","(-4625,3525)","0","pure_quanta_power","I140";
;
CDS_LIB"pure_quanta_power"
HDL_POWER"GND";
"A"5;
%"Q_RES"
"2","(-4625,3750)","0","pure_quanta","I141";
;
LOCATION"PR520"
$SEC"1"
CDS_SEC"1"
WATTAGE"1/8W"
MATERIAL"EMPTY"
TOLERANCE"1%"
VALUE"1.5"
PART_NUMBER"CS-1504FB00"
PACK_TYPE"0402LF"
CDS_LIB"pure_quanta";
"A"
$PN"1"38;
"B"
$PN"2"5;
%"Q_CAP"
"1","(-4625,4275)","0","pure_quanta","I142";
;
LOCATION"PC315"
$SEC"1"
CDS_SEC"1"
MATERIAL"EMPTY"
TOLERANCE"10%"
VALUE"560PF"
PART_NUMBER"CH1566K1B09"
VOLTAGE"50V"
PACK_TYPE"C0402"
CDS_LIB"pure_quanta";
"B"
$PN"2"38;
"A"
$PN"1"17;
%"UNIVERSAL_GND"
"1","(-4575,650)","0","pure_quanta_power","I143";
;
CDS_LIB"pure_quanta_power"
HDL_POWER"GND";
"A"6;
%"Q_RES"
"2","(-4575,875)","0","pure_quanta","I144";
;
LOCATION"PR519"
$SEC"1"
CDS_SEC"1"
WATTAGE"1/8W"
MATERIAL"EMPTY"
TOLERANCE"1%"
VALUE"1.5"
PART_NUMBER"CS-1504FB00"
PACK_TYPE"0402LF"
CDS_LIB"pure_quanta";
"A"
$PN"1"33;
"B"
$PN"2"6;
%"Q_CAP"
"1","(-4575,1375)","0","pure_quanta","I145";
;
LOCATION"PC255"
$SEC"1"
CDS_SEC"1"
MATERIAL"EMPTY"
TOLERANCE"10%"
VALUE"560PF"
PART_NUMBER"CH1566K1B09"
VOLTAGE"50V"
PACK_TYPE"C0402"
CDS_LIB"pure_quanta";
"B"
$PN"2"33;
"A"
$PN"1"15;
%"Q_RES"
"1","(-8450,5750)","1","pure_quanta","I146";
;
LOCATION"PR387"
$SEC"1"
CDS_SEC"1"
WATTAGE"1/16W"
MATERIAL"CHIP"
TOLERANCE"5%"
VALUE"0"
PART_NUMBER"CS00002JB38"
PACK_TYPE"0402LF"
CDS_LIB"pure_quanta";
"B"
$PN"2"7;
"A"
$PN"1"18;
%"VCC_CORE"
"1","(-8450,5950)","0","pure_quanta_power","I147";
;
HDL_POWER"P5V_STBY"
CDS_LIB"pure_quanta_power";
"A"7;
%"Q_RES"
"1","(-8100,5750)","1","pure_quanta","I148";
;
LOCATION"PR394"
$SEC"1"
CDS_SEC"1"
WATTAGE"1/16W"
MATERIAL"EMPTY"
TOLERANCE"5%"
VALUE"0"
PART_NUMBER"CS00002JB38"
PACK_TYPE"0402LF"
CDS_LIB"pure_quanta";
"B"
$PN"2"8;
"A"
$PN"1"18;
%"VCC_CORE"
"1","(-8100,5950)","0","pure_quanta_power","I149";
;
HDL_POWER"P3V3_STBY"
CDS_LIB"pure_quanta_power";
"A"8;
%"Q_RES"
"1","(-7225,4175)","0","pure_quanta","I15";
;
LOCATION"PR328"
$SEC"1"
CDS_SEC"1"
WATTAGE"1/16W"
MATERIAL"EMPTY"
TOLERANCE"1%"
VALUE"4.87K"
PART_NUMBER"CS24872FB07"
PACK_TYPE"0402LF"
CDS_LIB"pure_quanta";
"B"
$PN"2"42;
"A"
$PN"1"12;
%"VCC_CORE"
"1","(-7800,2825)","0","pure_quanta_power","I150";
;
HDL_POWER"PVDD11_S3_P1_PVCC"
CDS_LIB"pure_quanta_power";
"A"26;
%"Q_RES"
"2","(-1150,4275)","0","pure_quanta","I151";
;
LOCATION"PR395"
$SEC"1"
CDS_SEC"1"
WATTAGE"1/16W"
MATERIAL"CHIP"
TOLERANCE"1%"
VALUE"1K"
PART_NUMBER"TMP_QCS21002FB24"
PACK_TYPE"0402LF"
CDS_LIB"pure_quanta";
"A"
$PN"1"13;
"B"
$PN"2"57;
%"Q_CAPP"
"1","(-2200,2625)","0","pure_quanta","I152";
;
LOCATION"PC802"
$SEC"1"
CDS_SEC"1"
MATERIAL"SPCAP"
TOLERANCE"20%"
VALUE"470UF"
PART_NUMBER"CH747LM8825"
VOLTAGE"2.5V"
PACK_TYPE"SMLF"
CDS_LIB"pure_quanta";
"A"
$PN"1"53;
"B"
$PN"2"52;
%"Q_CAPP"
"1","(-825,2650)","0","pure_quanta","I153";
;
LOCATION"PC803"
$SEC"1"
CDS_SEC"1"
MATERIAL"OSCON"
TOLERANCE"20%"
VALUE"390UF"
PART_NUMBER"CC7390JMZ12"
VOLTAGE"2.5V"
PACK_TYPE"SMLF"
CDS_LIB"pure_quanta";
"A"
$PN"1"55;
"B"
$PN"2"56;
%"Q_RES"
"1","(-4800,4825)","0","pure_quanta","I19";
;
LOCATION"PR330"
$SEC"1"
CDS_SEC"1"
PACK_TYPE"0402LF"
TOLERANCE"1%"
MATERIAL"CHIP"
WATTAGE"1/16W"
VALUE"4.7"
PART_NUMBER"CS-4702FB19"
CDS_LIB"pure_quanta";
"B"
$PN"2"58;
"A"
$PN"1"48;
%"UNIVERSAL_GND"
"1","(-5450,3750)","0","pure_quanta_power","I2";
;
CDS_LIB"pure_quanta_power"
HDL_POWER"GND";
"A"36;
%"Q_CAP"
"1","(-5400,5375)","0","pure_quanta","I23";
;
LOCATION"PC509_1"
$SEC"1"
CDS_SEC"1"
MATERIAL"X6S"
TOLERANCE"10%"
VALUE"1UF"
PART_NUMBER"CH5104KEB02"
VOLTAGE"25V"
PACK_TYPE"C0402"
CDS_LIB"pure_quanta";
"B"
$PN"2"47;
"A"
$PN"1"46;
%"Q_CAP"
"1","(-4775,5375)","0","pure_quanta","I24";
;
LOCATION"PC513_1"
$SEC"1"
CDS_SEC"1"
MATERIAL"X6S"
TOLERANCE"10%"
VALUE"10UF"
PART_NUMBER"CH6104KEA00"
VOLTAGE"25V"
PACK_TYPE"C0805"
CDS_LIB"pure_quanta";
"B"
$PN"2"47;
"A"
$PN"1"46;
%"Q_CAP"
"1","(-4400,5375)","0","pure_quanta","I25";
;
LOCATION"PC515_1"
$SEC"1"
CDS_SEC"1"
MATERIAL"X6S"
TOLERANCE"10%"
VALUE"10UF"
PART_NUMBER"CH6104KEA00"
VOLTAGE"25V"
PACK_TYPE"C0805"
CDS_LIB"pure_quanta";
"B"
$PN"2"47;
"A"
$PN"1"46;
%"Q_CAP"
"1","(-4100,5375)","0","pure_quanta","I26";
;
LOCATION"PC517_1"
$SEC"1"
CDS_SEC"1"
MATERIAL"X6S"
TOLERANCE"10%"
VALUE"10UF"
PART_NUMBER"CH6104KEA00"
VOLTAGE"25V"
PACK_TYPE"C0805"
CDS_LIB"pure_quanta";
"B"
$PN"2"47;
"A"
$PN"1"46;
%"Q_CAPP"
"1","(-3375,5375)","0","pure_quanta","I27";
;
LOCATION"PC522"
$SEC"1"
CDS_SEC"1"
MATERIAL"OSCON"
TOLERANCE"20%"
VALUE"220UF"
PART_NUMBER"SP_CC72204MD02"
VOLTAGE"25V"
PACK_TYPE"THLF"
CDS_LIB"pure_quanta";
"A"
$PN"1"46;
"B"
$PN"2"47;
%"Q_CAP"
"1","(-2325,4300)","0","pure_quanta","I29";
;
LOCATION"PC524"
$SEC"1"
CDS_SEC"1"
MATERIAL"X7R"
TOLERANCE"10%"
VALUE"100NF"
PART_NUMBER"CH4106K1B01"
VOLTAGE"50V"
PACK_TYPE"C0402"
CDS_LIB"pure_quanta";
"B"
$PN"2"57;
"A"
$PN"1"13;
%"UNIVERSAL_GND"
"1","(-3900,5025)","0","pure_quanta_power","I31";
;
CDS_LIB"pure_quanta_power"
HDL_POWER"GND";
"A"47;
%"Q_INDUCTOR"
"1","(-2950,5575)","0","pure_quanta","I34";
;
LOCATION"PL56"
$SEC"1"
CDS_SEC"1"
MATERIAL"IND"
VALUE"100NH/16A"
PART_NUMBER"CV+10G0MZ12"
PACK_TYPE"SMLF"
CDS_LIB"pure_quanta"
NEEDS_NO_SIZE"TRUE";
"1"
$PN"1"46;
"2"
$PN"2"59;
%"VCC_CORE"
"1","(-2675,5625)","0","pure_quanta_power","I35";
;
HDL_POWER"P12V_STBY"
CDS_LIB"pure_quanta_power";
"A"59;
%"Q_CAP"
"1","(-2000,4300)","0","pure_quanta","I37";
;
LOCATION"PC526_1"
$SEC"1"
CDS_SEC"1"
MATERIAL"X6S"
TOLERANCE"20%"
VALUE"22UF"
PART_NUMBER"TMP_QCH622KMEA01"
VOLTAGE"4V"
PACK_TYPE"0805"
CDS_LIB"pure_quanta";
"B"
$PN"2"57;
"A"
$PN"1"13;
%"UNIVERSAL_GND"
"1","(-1150,3925)","0","pure_quanta_power","I38";
;
CDS_LIB"pure_quanta_power"
HDL_POWER"GND";
"A"57;
%"Q_CAP"
"1","(-1575,4300)","0","pure_quanta","I39";
;
LOCATION"PC529_1"
$SEC"1"
CDS_SEC"1"
MATERIAL"X6S"
TOLERANCE"20%"
VALUE"22UF"
PART_NUMBER"TMP_QCH622KMEA01"
VOLTAGE"4V"
PACK_TYPE"0805"
CDS_LIB"pure_quanta";
"B"
$PN"2"57;
"A"
$PN"1"13;
%"Q_CAP"
"1","(-7900,4200)","0","pure_quanta","I4";
;
LOCATION"PC503_1"
$SEC"1"
CDS_SEC"1"
MATERIAL"X7R"
TOLERANCE"10%"
VALUE"0.1UF"
PART_NUMBER"CH4104K1B00"
VOLTAGE"25V"
PACK_TYPE"0402"
CDS_LIB"pure_quanta";
"B"
$PN"2"10;
"A"
$PN"1"39;
%"VCC_CORE"
"1","(-1150,4600)","0","pure_quanta_power","I40";
;
HDL_POWER"PVDD11_S3_P1"
CDS_LIB"pure_quanta_power";
"A"13;
%"Q_CAP"
"1","(-3900,4700)","0","pure_quanta","I43";
;
LOCATION"PC519"
$SEC"1"
CDS_SEC"1"
MATERIAL"X7R"
TOLERANCE"10%"
VALUE"0.22UF"
PART_NUMBER"CH4223K1B00"
VOLTAGE"16V"
PACK_TYPE"0402"
CDS_LIB"pure_quanta";
"B"
$PN"2"16;
"A"
$PN"1"58;
%"ISL99390FRZTR5935"
"1","(-6075,4475)","0","pure_quanta","I44";
;
LOCATION"PU44"
$SEC"1"
CDS_SEC"1"
PART_TYPE"SMLF"
MATERIAL"IC"
VALUE"ISL99390FRZ-TR5935"
PART_NUMBER"AL099390004"
CDS_LIB"pure_quanta"
CDS_LMAN_SYM_OUTLINE"-300,700,250,-650"
NEEDS_NO_SIZE"TRUE";
"PGND2"
$PN"7_9-20_24"36;
"GL2"
$PN"41"44;
"GL1"
$PN"6"45;
"DNC"
$PN"31"43;
"EN"
$PN"35"40;
"PGND3"
$PN"40"36;
"VOS"
$PN"1"49;
"VIN2"
$PN"30"46;
"PGND1"
$PN"5"36;
"SW"
$PN"10_19"17;
"LSET"
$PN"37"42;
"IOUT"
$PN"38"41;
"TOUT_FLT"
$PN"36"28;
"PVCC"
$PN"4"18;
"PHASE"
$PN"32"16;
"VIN1"
$PN"25_29"46;
"BOOT"
$PN"33"48;
"AGND"
$PN"2"36;
"VCC"
$PN"3"40;
"REFIN"
$PN"39"39;
"PWM"
$PN"34"27;
%"UNIVERSAL_GND"
"1","(-5450,825)","0","pure_quanta_power","I46";
;
CDS_LIB"pure_quanta_power"
HDL_POWER"GND";
"A"29;
%"Q_CAP"
"1","(-7850,1275)","0","pure_quanta","I48";
;
LOCATION"PC504_2"
$SEC"1"
CDS_SEC"1"
MATERIAL"X7R"
TOLERANCE"10%"
VALUE"0.1UF"
PART_NUMBER"CH4104K1B00"
VOLTAGE"25V"
PACK_TYPE"0402"
CDS_LIB"pure_quanta";
"B"
$PN"2"9;
"A"
$PN"1"19;
%"UNIVERSAL_GND"
"1","(-7850,1000)","0","pure_quanta_power","I49";
;
CDS_LIB"pure_quanta_power"
HDL_POWER"GND";
"A"9;
%"UNIVERSAL_GND"
"1","(-7900,3925)","0","pure_quanta_power","I5";
;
CDS_LIB"pure_quanta_power"
HDL_POWER"GND";
"A"10;
%"UNIVERSAL_GND"
"1","(-7525,1075)","0","pure_quanta_power","I50";
;
CDS_LIB"pure_quanta_power"
HDL_POWER"GND";
"A"11;
%"Q_RES"
"1","(-7200,1250)","0","pure_quanta","I52";
;
LOCATION"PR329"
$SEC"1"
CDS_SEC"1"
WATTAGE"1/16W"
MATERIAL"EMPTY"
TOLERANCE"1%"
VALUE"4.87K"
PART_NUMBER"CS24872FB07"
PACK_TYPE"0402LF"
CDS_LIB"pure_quanta";
"B"
$PN"2"22;
"A"
$PN"1"11;
%"UNIVERSAL_GND"
"1","(-7550,4000)","0","pure_quanta_power","I6";
;
CDS_LIB"pure_quanta_power"
HDL_POWER"GND";
"A"12;
%"Q_RES"
"1","(-4675,1900)","0","pure_quanta","I63";
;
LOCATION"PR331"
$SEC"1"
CDS_SEC"1"
PACK_TYPE"0402LF"
TOLERANCE"1%"
MATERIAL"CHIP"
WATTAGE"1/16W"
VALUE"4.7"
PART_NUMBER"CS-4702FB19"
CDS_LIB"pure_quanta";
"B"
$PN"2"50;
"A"
$PN"1"32;
%"Q_CAP"
"1","(-3800,1775)","0","pure_quanta","I66";
;
LOCATION"PC520"
$SEC"1"
CDS_SEC"1"
MATERIAL"X7R"
TOLERANCE"10%"
VALUE"0.22UF"
PART_NUMBER"CH4223K1B00"
VOLTAGE"16V"
PACK_TYPE"0402"
CDS_LIB"pure_quanta";
"B"
$PN"2"14;
"A"
$PN"1"50;
%"Q_CAP"
"1","(-5350,2450)","0","pure_quanta","I67";
;
LOCATION"PC510_2"
$SEC"1"
CDS_SEC"1"
MATERIAL"X6S"
TOLERANCE"10%"
VALUE"1UF"
PART_NUMBER"CH5104KEB02"
VOLTAGE"25V"
PACK_TYPE"C0402"
CDS_LIB"pure_quanta";
"B"
$PN"2"37;
"A"
$PN"1"35;
%"Q_CAP"
"1","(-4700,2450)","0","pure_quanta","I69";
;
LOCATION"PC514_2"
$SEC"1"
CDS_SEC"1"
MATERIAL"X6S"
TOLERANCE"10%"
VALUE"10UF"
PART_NUMBER"CH6104KEA00"
VOLTAGE"25V"
PACK_TYPE"C0805"
CDS_LIB"pure_quanta";
"B"
$PN"2"37;
"A"
$PN"1"35;
%"Q_CAP"
"1","(-4400,2450)","0","pure_quanta","I70";
;
LOCATION"PC516_2"
$SEC"1"
CDS_SEC"1"
MATERIAL"X6S"
TOLERANCE"10%"
VALUE"10UF"
PART_NUMBER"CH6104KEA00"
VOLTAGE"25V"
PACK_TYPE"C0805"
CDS_LIB"pure_quanta";
"B"
$PN"2"37;
"A"
$PN"1"35;
%"UNIVERSAL_GND"
"1","(-3750,2150)","0","pure_quanta_power","I71";
;
CDS_LIB"pure_quanta_power"
HDL_POWER"GND";
"A"37;
%"VCC_CORE"
"1","(-3750,2725)","0","pure_quanta_power","I73";
;
HDL_POWER"SW_P12V_STBY_PVDD11_S3_P1_FLT"
CDS_LIB"pure_quanta_power";
"A"35;
%"Q_CAP"
"1","(-2400,1375)","0","pure_quanta","I79";
;
LOCATION"PC523_2"
$SEC"1"
CDS_SEC"1"
MATERIAL"X6S"
TOLERANCE"20%"
VALUE"22UF"
PART_NUMBER"TMP_QCH622KMEA01"
VOLTAGE"4V"
PACK_TYPE"0805"
CDS_LIB"pure_quanta";
"B"
$PN"2"54;
"A"
$PN"1"51;
%"UNIVERSAL_GND"
"1","(-1975,1025)","0","pure_quanta_power","I80";
;
CDS_LIB"pure_quanta_power"
HDL_POWER"GND";
"A"54;
%"Q_CAP"
"1","(-1975,1375)","0","pure_quanta","I81";
;
LOCATION"PC527_2"
$SEC"1"
CDS_SEC"1"
MATERIAL"X6S"
TOLERANCE"20%"
VALUE"22UF"
PART_NUMBER"TMP_QCH622KMEA01"
VOLTAGE"4V"
PACK_TYPE"0805"
CDS_LIB"pure_quanta";
"B"
$PN"2"54;
"A"
$PN"1"51;
%"VCC_CORE"
"1","(-1975,1700)","0","pure_quanta_power","I82";
;
HDL_POWER"PVDD11_S3_P1"
CDS_LIB"pure_quanta_power";
"A"51;
%"ISL99390FRZTR5935"
"1","(-6025,1550)","0","pure_quanta","I84";
;
LOCATION"PU45"
$SEC"1"
CDS_SEC"1"
PART_TYPE"SMLF"
MATERIAL"IC"
VALUE"ISL99390FRZ-TR5935"
PART_NUMBER"AL099390004"
NEEDS_NO_SIZE"TRUE"
CDS_LMAN_SYM_OUTLINE"-300,700,250,-650"
CDS_LIB"pure_quanta";
"PGND2"
$PN"7_9-20_24"29;
"GL2"
$PN"41"31;
"GL1"
$PN"6"30;
"DNC"
$PN"31"23;
"EN"
$PN"35"21;
"PGND3"
$PN"40"29;
"VOS"
$PN"1"34;
"VIN2"
$PN"30"35;
"PGND1"
$PN"5"29;
"SW"
$PN"10_19"15;
"LSET"
$PN"37"22;
"IOUT"
$PN"38"25;
"TOUT_FLT"
$PN"36"24;
"PVCC"
$PN"4"26;
"PHASE"
$PN"32"14;
"VIN1"
$PN"25_29"35;
"BOOT"
$PN"33"32;
"AGND"
$PN"2"29;
"VCC"
$PN"3"21;
"REFIN"
$PN"39"19;
"PWM"
$PN"34"20;
%"UNIVERSAL_GND"
"1","(-2900,2300)","0","pure_quanta_power","I90";
;
CDS_LIB"pure_quanta_power"
HDL_POWER"GND";
"A"52;
%"VCC_CORE"
"1","(-2900,2875)","0","pure_quanta_power","I93";
;
HDL_POWER"PVDD11_S3_P1"
CDS_LIB"pure_quanta_power";
"A"53;
%"Q_CAPP"
"1","(-2900,2625)","0","pure_quanta","I98";
;
LOCATION"PC525"
$SEC"1"
CDS_SEC"1"
MATERIAL"SPCAP"
TOLERANCE"20%"
VALUE"470UF"
PART_NUMBER"CH747LM8825"
VOLTAGE"2.5V"
PACK_TYPE"SMLF"
CDS_LIB"pure_quanta";
"A"
$PN"1"53;
"B"
$PN"2"52;
END.
